(kicad_pcb
	(version 20241229)
	(generator "pcbnew")
	(generator_version "9.0")
	(general
		(thickness 1.711)
		(legacy_teardrops no)
	)
	(paper "A4")
	(title_block
		(title "Antmicro Baseboard for Jetson AGX Thor")
		(date "2026-02-18")
		(rev "1.1.0")
		(company "Antmicro Ltd")
		(comment 1 "www.antmicro.com")
		(comment 9 "footprints 260-263 of 1170")
	)
	(layers
		(0 "F.Cu" signal)
		(4 "In1.Cu" signal)
		(6 "In2.Cu" signal)
		(8 "In3.Cu" signal)
		(10 "In4.Cu" jumper)
		(12 "In5.Cu" signal)
		(14 "In6.Cu" signal)
		(16 "In7.Cu" signal)
		(18 "In8.Cu" signal)
		(2 "B.Cu" signal)
		(9 "F.Adhes" user "F.Adhesive")
		(11 "B.Adhes" user "B.Adhesive")
		(13 "F.Paste" user)
		(15 "B.Paste" user)
		(5 "F.SilkS" user "F.Silkscreen")
		(7 "B.SilkS" user "B.Silkscreen")
		(1 "F.Mask" user)
		(3 "B.Mask" user)
		(17 "Dwgs.User" user "User.Drawings")
		(19 "Cmts.User" user "User.Comments")
		(21 "Eco1.User" user "User.Eco1")
		(23 "Eco2.User" user "User.Eco2")
		(25 "Edge.Cuts" user)
		(27 "Margin" user)
		(31 "F.CrtYd" user "F.Courtyard")
		(29 "B.CrtYd" user "B.Courtyard")
		(35 "F.Fab" user)
		(33 "B.Fab" user)
	)
	(footprint "antmicro-footprints:Vishay_PowerPAK_1212-8_Single"
		(layer "F.Cu")
		(at 114.016 60.91)
		(descr "PowerPAK 1212-8 Single")
		(tags "Vishay PowerPAK 1212-8 Single")
		(property "Reference" "Q9"
			(at 3.694 2.47 0)
			(layer "F.SilkS")
			(effects
				(font
					(size 0.7 0.7)
					(thickness 0.15)
				)
				(justify right top)
			)
		)
		(property "Value" "SISS05DN-T1-GE3"
			(at 0 2.7 0)
			(layer "F.Fab")
			(effects
				(font
					(size 0.7 0.7)
					(thickness 0.15)
				)
				(justify left bottom)
			)
		)
		(property "Datasheet" "https://www.vishay.com/docs/77029/siss05dn.pdf"
			(at 0 0 0)
			(layer "F.Fab")
			(hide yes)
			(effects
				(font
					(size 1.27 1.27)
					(thickness 0.15)
				)
			)
		)
		(property "Description" "Power MOSFET, P Channel, 30 V, 108 A, 0.0035 ohm, PowerPAK 1212, Surface Mount"
			(at 0 0 0)
			(layer "F.Fab")
			(hide yes)
			(effects
				(font
					(size 1.27 1.27)
					(thickness 0.15)
				)
			)
		)
		(property "MPN" "SISS05DN-T1-GE3"
			(at 0 0 0)
			(unlocked yes)
			(layer "F.Fab")
			(hide yes)
			(effects
				(font
					(size 1 1)
					(thickness 0.15)
				)
			)
		)
		(property "Manufacturer" "Vishay"
			(at 0 0 0)
			(unlocked yes)
			(layer "F.Fab")
			(hide yes)
			(effects
				(font
					(size 1 1)
					(thickness 0.15)
				)
			)
		)
		(property "Author" "Antmicro"
			(at 0 0 0)
			(unlocked yes)
			(layer "F.Fab")
			(hide yes)
			(effects
				(font
					(size 1 1)
					(thickness 0.15)
				)
			)
		)
		(property "License" "Apache-2.0"
			(at 0 0 0)
			(unlocked yes)
			(layer "F.Fab")
			(hide yes)
			(effects
				(font
					(size 1 1)
					(thickness 0.15)
				)
			)
		)
		(sheetname "/SoM_Power/")
		(sheetfile "som_power.kicad_sch")
		(attr smd)
		(fp_line
			(start -1.651 -1.651)
			(end -1.651 -1.317)
			(stroke
				(width 0.15)
				(type solid)
			)
			(layer "F.SilkS")
		)
		(fp_line
			(start -1.651 -1.651)
			(end 1.648 -1.651)
			(stroke
				(width 0.15)
				(type solid)
			)
			(layer "F.SilkS")
		)
		(fp_line
			(start -1.635 1.3)
			(end -1.635 1.634)
			(stroke
				(width 0.15)
				(type solid)
			)
			(layer "F.SilkS")
		)
		(fp_line
			(start -1.635 1.634)
			(end 1.634 1.634)
			(stroke
				(width 0.15)
				(type solid)
			)
			(layer "F.SilkS")
		)
		(fp_line
			(start 1.634 1.3)
			(end 1.634 1.634)
			(stroke
				(width 0.15)
				(type solid)
			)
			(layer "F.SilkS")
		)
		(fp_line
			(start 1.648 -1.651)
			(end 1.648 -1.317001)
			(stroke
				(width 0.15)
				(type solid)
			)
			(layer "F.SilkS")
		)
		(fp_circle
			(center -1.899999 -1.4)
			(end -1.85 -1.4)
			(stroke
				(width 0.15)
				(type solid)
			)
			(fill yes)
			(layer "F.SilkS")
		)
		(fp_poly
			(pts
				(xy -2 -1.8) (xy 2 -1.8) (xy 2.000001 1.798) (xy -2.000001 1.798)
			)
			(stroke
				(width 0.05)
				(type solid)
			)
			(fill no)
			(layer "F.CrtYd")
		)
		(fp_line
			(start -1.6425 -1.4175)
			(end -1.4175 -1.6425)
			(stroke
				(width 0.15)
				(type solid)
			)
			(layer "F.Fab")
		)
		(fp_poly
			(pts
				(xy -1.651 -1.651) (xy 1.648 -1.651) (xy 1.648 1.648) (xy -1.651 1.648)
			)
			(stroke
				(width 0.15)
				(type solid)
			)
			(fill no)
			(layer "F.Fab")
		)
		(fp_text user "${REFERENCE}"
			(at -8 4.7 0)
			(layer "F.Fab")
			(effects
				(font
					(size 0.7 0.7)
					(thickness 0.15)
				)
				(justify left bottom)
			)
		)
		(fp_text user "License: Apache-2.0"
			(at -8 7.1 0)
			(layer "F.Fab")
			(effects
				(font
					(size 0.7 0.7)
					(thickness 0.15)
				)
				(justify left bottom)
			)
		)
		(fp_text user "Author: Antmicro"
			(at -8 5.9 0)
			(layer "F.Fab")
			(effects
				(font
					(size 0.7 0.7)
					(thickness 0.15)
				)
				(justify left bottom)
			)
		)
		(pad "1" smd rect
			(at -1.436 -0.99)
			(size 0.99 0.405)
			(layers "F.Cu" "F.Mask" "F.Paste")
			(net 491 "+5V_AON")
			(pinfunction "S")
			(pintype "passive")
		)
		(pad "2" smd rect
			(at -1.436 -0.332)
			(size 0.99 0.405)
			(layers "F.Cu" "F.Mask" "F.Paste")
			(net 491 "+5V_AON")
			(pinfunction "S")
			(pintype "passive")
		)
		(pad "3" smd rect
			(at -1.436 0.33)
			(size 0.99 0.405)
			(layers "F.Cu" "F.Mask" "F.Paste")
			(net 491 "+5V_AON")
			(pinfunction "S")
			(pintype "passive")
		)
		(pad "4" smd rect
			(at -1.436 0.988)
			(size 0.99 0.405)
			(layers "F.Cu" "F.Mask" "F.Paste")
			(net 1392 "Net-(Q6-D)")
			(pinfunction "G")
			(pintype "input")
		)
		(pad "5" smd custom
			(at 0.556999 0)
			(size 1.725 2.235)
			(layers "F.Cu" "F.Mask" "F.Paste")
			(net 1096 "Net-(Q9-D)")
			(pinfunction "D")
			(pintype "passive")
			(zone_connect 2)
			(options
				(clearance outline)
				(anchor rect)
			)
			(primitives
				(gr_poly
					(pts
						(xy 0.8625 0.1275) (xy 0.8625 -0.1275) (xy 1.3725 -0.1275) (xy 1.3725 -0.5325) (xy 0.8625 -0.5325)
						(xy 0.8625 -0.7875) (xy 1.3725 -0.7875) (xy 1.3725 -1.195) (xy 0.6125 -1.195) (xy 0.6125 1.195)
						(xy 1.3725 1.195) (xy 1.3725 0.7875) (xy 0.8625 0.7875) (xy 0.8625 0.5325) (xy 1.3725 0.5325)
						(xy 1.3725 0.1275)
					)
					(width 0)
					(fill yes)
				)
			)
		)
	)
	(footprint "antmicro-footprints:C_0402_1005Metric"
		(layer "F.Cu")
		(at 160.369468 79.51 180)
		(descr "Capacitor SMD 0402")
		(tags "capacitor SMD 0402")
		(property "Reference" "C304"
			(at 3.569468 0.31 0)
			(layer "F.SilkS")
			(effects
				(font
					(size 0.7 0.7)
					(thickness 0.15)
				)
				(justify right top)
			)
		)
		(property "Value" "C_100n_0402"
			(at -1.022927 2.155213 0)
			(layer "F.Fab")
			(effects
				(font
					(size 0.7 0.7)
					(thickness 0.15)
				)
				(justify right top)
			)
		)
		(property "Datasheet" "https://www.murata.com/products/productdetail?partno=GRM155R61H104KE14%23"
			(at 0 0 0)
			(layer "F.Fab")
			(hide yes)
			(effects
				(font
					(size 1.27 1.27)
					(thickness 0.15)
				)
			)
		)
		(property "Description" "SMD Multilayer Ceramic Capacitor, 0.1 µF, 50 V, 0402 [1005 Metric], ± 10%, X5R, GRM Series"
			(at 0 0 0)
			(layer "F.Fab")
			(hide yes)
			(effects
				(font
					(size 1.27 1.27)
					(thickness 0.15)
				)
			)
		)
		(property "MPN" "GRM155R61H104KE14D"
			(at 0 0 180)
			(unlocked yes)
			(layer "F.Fab")
			(hide yes)
			(effects
				(font
					(size 1 1)
					(thickness 0.15)
				)
			)
		)
		(property "Manufacturer" "Murata"
			(at 0 0 180)
			(unlocked yes)
			(layer "F.Fab")
			(hide yes)
			(effects
				(font
					(size 1 1)
					(thickness 0.15)
				)
			)
		)
		(property "License" "Apache-2.0"
			(at 0 0 180)
			(unlocked yes)
			(layer "F.Fab")
			(hide yes)
			(effects
				(font
					(size 1 1)
					(thickness 0.15)
				)
			)
		)
		(property "Author" "Antmicro"
			(at 0 0 180)
			(unlocked yes)
			(layer "F.Fab")
			(hide yes)
			(effects
				(font
					(size 1 1)
					(thickness 0.15)
				)
			)
		)
		(property "Val" "100n"
			(at 0 0 180)
			(unlocked yes)
			(layer "F.Fab")
			(hide yes)
			(effects
				(font
					(size 1 1)
					(thickness 0.15)
				)
			)
		)
		(property "Voltage" "50V"
			(at 0 0 180)
			(unlocked yes)
			(layer "F.Fab")
			(hide yes)
			(effects
				(font
					(size 1 1)
					(thickness 0.15)
				)
			)
		)
		(property "Dielectric" "X5R"
			(at 0 0 180)
			(unlocked yes)
			(layer "F.Fab")
			(hide yes)
			(effects
				(font
					(size 1 1)
					(thickness 0.15)
				)
			)
		)
		(property "Public" "False"
			(at 0 0 180)
			(unlocked yes)
			(layer "F.Fab")
			(hide yes)
			(effects
				(font
					(size 1 1)
					(thickness 0.15)
				)
			)
		)
		(component_classes
			(class "DCDC_20V")
		)
		(sheetname "/DCDC/")
		(sheetfile "dcdc.kicad_sch")
		(attr smd)
		(fp_rect
			(start -0.925 -0.47)
			(end 0.925 0.47)
			(stroke
				(width 0.05)
				(type default)
			)
			(fill no)
			(layer "F.CrtYd")
		)
		(fp_line
			(start 0.504 0.248)
			(end -0.494 0.248)
			(stroke
				(width 0.15)
				(type solid)
			)
			(layer "F.Fab")
		)
		(fp_line
			(start 0.504 -0.25)
			(end 0.504 0.248)
			(stroke
				(width 0.15)
				(type solid)
			)
			(layer "F.Fab")
		)
		(fp_line
			(start -0.494 0.248)
			(end -0.494 -0.25)
			(stroke
				(width 0.15)
				(type solid)
			)
			(layer "F.Fab")
		)
		(fp_line
			(start -0.494 -0.25)
			(end 0.504 -0.25)
			(stroke
				(width 0.15)
				(type solid)
			)
			(layer "F.Fab")
		)
		(fp_text user "License: Apache-2.0"
			(at -0.939 5.799 0)
			(layer "F.Fab")
			(effects
				(font
					(size 0.7 0.7)
					(thickness 0.15)
				)
				(justify right top)
			)
		)
		(fp_text user "Author: Antmicro"
			(at -0.939 3.399 0)
			(layer "F.Fab")
			(effects
				(font
					(size 0.7 0.7)
					(thickness 0.15)
				)
				(justify right top)
			)
		)
		(fp_text user "${REFERENCE}"
			(at -0.939 4.599 0)
			(layer "F.Fab")
			(effects
				(font
					(size 0.7 0.7)
					(thickness 0.15)
				)
				(justify right top)
			)
		)
		(pad "1" smd roundrect
			(at -0.48 0 180)
			(size 0.59 0.64)
			(layers "F.Cu" "F.Mask" "F.Paste")
			(roundrect_rratio 0.25)
			(net 1 "GND")
			(pintype "passive")
		)
		(pad "2" smd roundrect
			(at 0.48 0 180)
			(size 0.59 0.64)
			(layers "F.Cu" "F.Mask" "F.Paste")
			(roundrect_rratio 0.25)
			(net 4 "+3V3_AON")
			(pintype "passive")
		)
	)
	(footprint "antmicro-footprints:R_0402_1005Metric"
		(layer "F.Cu")
		(at 147 112)
		(descr "Resistor SMD 0402")
		(tags "resistor SMD 0402")
		(property "Reference" "R353"
			(at -3.6 0.4 0)
			(layer "F.SilkS")
			(effects
				(font
					(size 0.7 0.7)
					(thickness 0.15)
				)
				(justify left bottom)
			)
		)
		(property "Value" "R_2k2_0402"
			(at -1.011843 1.772047 0)
			(layer "F.Fab")
			(effects
				(font
					(size 0.7 0.7)
					(thickness 0.15)
				)
				(justify left bottom)
			)
		)
		(property "Datasheet" "https://www.bourns.com/docs/product-datasheets/cr.pdf"
			(at 0 0 0)
			(layer "F.Fab")
			(hide yes)
			(effects
				(font
					(size 1.27 1.27)
					(thickness 0.15)
				)
			)
		)
		(property "Description" "SMD Chip Resistor, 2.2 kohm, ± 1%, 62.5 mW, 0402 [1005 Metric], Thick Film, General Purpose"
			(at 0 0 0)
			(layer "F.Fab")
			(hide yes)
			(effects
				(font
					(size 1.27 1.27)
					(thickness 0.15)
				)
			)
		)
		(property "MPN" "CR0402-FX-2201GLF"
			(at 0 0 0)
			(unlocked yes)
			(layer "F.Fab")
			(hide yes)
			(effects
				(font
					(size 1 1)
					(thickness 0.15)
				)
			)
		)
		(property "Manufacturer" "Bourns"
			(at 0 0 0)
			(unlocked yes)
			(layer "F.Fab")
			(hide yes)
			(effects
				(font
					(size 1 1)
					(thickness 0.15)
				)
			)
		)
		(property "License" "Apache-2.0"
			(at 0 0 0)
			(unlocked yes)
			(layer "F.Fab")
			(hide yes)
			(effects
				(font
					(size 1 1)
					(thickness 0.15)
				)
			)
		)
		(property "Author" "Antmicro"
			(at 0 0 0)
			(unlocked yes)
			(layer "F.Fab")
			(hide yes)
			(effects
				(font
					(size 1 1)
					(thickness 0.15)
				)
			)
		)
		(property "Val" "2k2"
			(at 0 0 0)
			(unlocked yes)
			(layer "F.Fab")
			(hide yes)
			(effects
				(font
					(size 1 1)
					(thickness 0.15)
				)
			)
		)
		(property "Tolerance" "1%"
			(at 0 0 0)
			(unlocked yes)
			(layer "F.Fab")
			(hide yes)
			(effects
				(font
					(size 1 1)
					(thickness 0.15)
				)
			)
		)
		(sheetname "/SoM_IO/")
		(sheetfile "som_io.kicad_sch")
		(attr smd exclude_from_pos_files exclude_from_bom dnp)
		(fp_rect
			(start -0.925 -0.47)
			(end 0.925 0.47)
			(stroke
				(width 0.05)
				(type default)
			)
			(fill no)
			(layer "F.CrtYd")
		)
		(fp_rect
			(start -0.5 -0.25)
			(end 0.5 0.25)
			(stroke
				(width 0.15)
				(type solid)
			)
			(fill no)
			(layer "F.Fab")
		)
		(fp_text user "Author: Antmicro"
			(at -0.95 4.169 0)
			(layer "F.Fab")
			(effects
				(font
					(size 0.7 0.7)
					(thickness 0.15)
				)
				(justify left bottom)
			)
		)
		(fp_text user "License: Apache-2.0"
			(at -0.95 5.169 0)
			(layer "F.Fab")
			(effects
				(font
					(size 0.7 0.7)
					(thickness 0.15)
				)
				(justify left bottom)
			)
		)
		(fp_text user "${REFERENCE}"
			(at -0.95 3.168 0)
			(layer "F.Fab")
			(effects
				(font
					(size 0.7 0.7)
					(thickness 0.15)
				)
				(justify left bottom)
			)
		)
		(pad "1" smd roundrect
			(at -0.48 0)
			(size 0.59 0.64)
			(layers "F.Cu" "F.Mask" "F.Paste")
			(roundrect_rratio 0.25)
			(net 11 "+1V8")
			(pintype "passive")
		)
		(pad "2" smd roundrect
			(at 0.48 0)
			(size 0.59 0.64)
			(layers "F.Cu" "F.Mask" "F.Paste")
			(roundrect_rratio 0.25)
			(net 133 "/SoM_IO/I2C5_SCL_1V8")
			(pintype "passive")
		)
	)
	(footprint "antmicro-footprints:C_0402_1005Metric"
		(layer "F.Cu")
		(at 182.764468 89.705 -90)
		(descr "Capacitor SMD 0402")
		(tags "capacitor SMD 0402")
		(property "Reference" "C244"
			(at -1 -1.65 90)
			(layer "F.SilkS")
			(effects
				(font
					(size 0.7 0.7)
					(thickness 0.15)
				)
				(justify right top)
			)
		)
		(property "Value" "C_1u_0402"
			(at -1.022927 2.155213 90)
			(layer "F.Fab")
			(effects
				(font
					(size 0.7 0.7)
					(thickness 0.15)
				)
				(justify right top)
			)
		)
		(property "Datasheet" "https://product.tdk.com/en/search/capacitor/ceramic/mlcc/info?part_no=C1005X6S1A105K050BC"
			(at 0 0 90)
			(layer "F.Fab")
			(hide yes)
			(effects
				(font
					(size 1.27 1.27)
					(thickness 0.15)
				)
			)
		)
		(property "Description" "SMD Multilayer Ceramic Capacitor, 1 µF, 10 V, 0402 [1005 Metric], ± 10%, X6S, C"
			(at 0 0 90)
			(layer "F.Fab")
			(hide yes)
			(effects
				(font
					(size 1.27 1.27)
					(thickness 0.15)
				)
			)
		)
		(property "Manufacturer" "TDK"
			(at 0 0 270)
			(unlocked yes)
			(layer "F.Fab")
			(hide yes)
			(effects
				(font
					(size 1 1)
					(thickness 0.15)
				)
			)
		)
		(property "MPN" "C1005X6S1A105K050BC"
			(at 0 0 270)
			(unlocked yes)
			(layer "F.Fab")
			(hide yes)
			(effects
				(font
					(size 1 1)
					(thickness 0.15)
				)
			)
		)
		(property "Val" "1u"
			(at 0 0 270)
			(unlocked yes)
			(layer "F.Fab")
			(hide yes)
			(effects
				(font
					(size 1 1)
					(thickness 0.15)
				)
			)
		)
		(property "License" "Apache-2.0"
			(at 0 0 270)
			(unlocked yes)
			(layer "F.Fab")
			(hide yes)
			(effects
				(font
					(size 1 1)
					(thickness 0.15)
				)
			)
		)
		(property "Author" "Antmicro"
			(at 0 0 270)
			(unlocked yes)
			(layer "F.Fab")
			(hide yes)
			(effects
				(font
					(size 1 1)
					(thickness 0.15)
				)
			)
		)
		(property "Voltage" ""
			(at 0 0 270)
			(unlocked yes)
			(layer "F.Fab")
			(hide yes)
			(effects
				(font
					(size 1 1)
					(thickness 0.15)
				)
			)
		)
		(property "Dielectric" ""
			(at 0 0 270)
			(unlocked yes)
			(layer "F.Fab")
			(hide yes)
			(effects
				(font
					(size 1 1)
					(thickness 0.15)
				)
			)
		)
		(component_classes
			(class "DCDC_SOM")
		)
		(sheetname "/DCDC/")
		(sheetfile "dcdc.kicad_sch")
		(attr smd)
		(fp_rect
			(start -0.925 -0.47)
			(end 0.925 0.47)
			(stroke
				(width 0.05)
				(type default)
			)
			(fill no)
			(layer "F.CrtYd")
		)
		(fp_line
			(start -0.494 0.248)
			(end -0.494 -0.25)
			(stroke
				(width 0.15)
				(type solid)
			)
			(layer "F.Fab")
		)
		(fp_line
			(start 0.504 0.248)
			(end -0.494 0.248)
			(stroke
				(width 0.15)
				(type solid)
			)
			(layer "F.Fab")
		)
		(fp_line
			(start -0.494 -0.25)
			(end 0.504 -0.25)
			(stroke
				(width 0.15)
				(type solid)
			)
			(layer "F.Fab")
		)
		(fp_line
			(start 0.504 -0.25)
			(end 0.504 0.248)
			(stroke
				(width 0.15)
				(type solid)
			)
			(layer "F.Fab")
		)
		(fp_text user "${REFERENCE}"
			(at -0.939 4.599 90)
			(layer "F.Fab")
			(effects
				(font
					(size 0.7 0.7)
					(thickness 0.15)
				)
				(justify right top)
			)
		)
		(fp_text user "Author: Antmicro"
			(at -0.939 3.399 90)
			(layer "F.Fab")
			(effects
				(font
					(size 0.7 0.7)
					(thickness 0.15)
				)
				(justify right top)
			)
		)
		(fp_text user "License: Apache-2.0"
			(at -0.939 5.799 90)
			(layer "F.Fab")
			(effects
				(font
					(size 0.7 0.7)
					(thickness 0.15)
				)
				(justify right top)
			)
		)
		(pad "1" smd roundrect
			(at -0.48 0 270)
			(size 0.59 0.64)
			(layers "F.Cu" "F.Mask" "F.Paste")
			(roundrect_rratio 0.25)
			(net 1 "GND")
			(pintype "passive")
		)
		(pad "2" smd roundrect
			(at 0.48 0 270)
			(size 0.59 0.64)
			(layers "F.Cu" "F.Mask" "F.Paste")
			(roundrect_rratio 0.25)
			(net 896 "/DCDC/16V_VDD")
			(pintype "passive")
		)
	)
)
